(kicad_pcb
	(version 20241229)
	(generator "pcbnew")
	(generator_version "9.0")
	(general
		(thickness 1.6)
		(legacy_teardrops no)
	)
	(paper "A4")
	(title_block
		(title "environment-sensor")
		(comment 1 "footprints 60-62 of 109")
	)
	(layers
		(0 "F.Cu" signal)
		(4 "In1.Cu" signal)
		(6 "In2.Cu" signal)
		(2 "B.Cu" signal)
		(9 "F.Adhes" user "F.Adhesive")
		(11 "B.Adhes" user "B.Adhesive")
		(13 "F.Paste" user)
		(15 "B.Paste" user)
		(5 "F.SilkS" user "F.Silkscreen")
		(7 "B.SilkS" user "B.Silkscreen")
		(1 "F.Mask" user)
		(3 "B.Mask" user)
		(17 "Dwgs.User" user "User.Drawings")
		(19 "Cmts.User" user "User.Comments")
		(21 "Eco1.User" user "User.Eco1")
		(23 "Eco2.User" user "User.Eco2")
		(25 "Edge.Cuts" user)
		(27 "Margin" user)
		(31 "F.CrtYd" user "F.Courtyard")
		(29 "B.CrtYd" user "B.Courtyard")
		(35 "F.Fab" user)
		(33 "B.Fab" user)
	)
	(footprint "antmicro-footprints:FB_0603_1608Metric"
		(layer "F.Cu")
		(at 169.25 138.7)
		(property "Reference" "FB2"
			(at -3.45 0.45 0)
			(layer "F.SilkS")
			(effects
				(font
					(size 0.7 0.7)
					(thickness 0.15)
				)
				(justify left bottom)
			)
		)
		(property "Value" "FB_120Z_2A_Murata-BLM18PG_0603"
			(at 0 1.5 0)
			(layer "F.Fab")
			(effects
				(font
					(size 0.7 0.7)
					(thickness 0.15)
				)
				(justify left bottom)
			)
		)
		(property "Description" "Ferrite Bead, 0603 [1608 Metric], 120 ohm, 2 A, BLM18P, 0.05 ohm, ± 25%, DC power line"
			(at 0 0 0)
			(layer "F.Fab")
			(hide yes)
			(effects
				(font
					(size 1.27 1.27)
					(thickness 0.15)
				)
			)
		)
		(property "Author" "Antmicro"
			(at 0 0 0)
			(layer "F.Fab")
			(hide yes)
			(effects
				(font
					(size 1 1)
					(thickness 0.15)
				)
			)
		)
		(property "Current" ""
			(at 0 0 0)
			(layer "F.Fab")
			(hide yes)
			(effects
				(font
					(size 1 1)
					(thickness 0.15)
				)
			)
		)
		(property "License" "Apache-2.0"
			(at 0 0 0)
			(layer "F.Fab")
			(hide yes)
			(effects
				(font
					(size 1 1)
					(thickness 0.15)
				)
			)
		)
		(property "MPN" "BLM18PG121SN1D"
			(at 0 0 0)
			(layer "F.Fab")
			(hide yes)
			(effects
				(font
					(size 1 1)
					(thickness 0.15)
				)
			)
		)
		(property "Manufacturer" "Murata"
			(at 0 0 0)
			(layer "F.Fab")
			(hide yes)
			(effects
				(font
					(size 1 1)
					(thickness 0.15)
				)
			)
		)
		(property "Public" "False"
			(at 0 0 0)
			(layer "F.Fab")
			(hide yes)
			(effects
				(font
					(size 1 1)
					(thickness 0.15)
				)
			)
		)
		(property "Val" "120Z/2A"
			(at 0 0 0)
			(layer "F.Fab")
			(hide yes)
			(effects
				(font
					(size 1 1)
					(thickness 0.15)
				)
			)
		)
		(sheetfile "environment-sensor.kicad_sch")
		(attr smd)
		(fp_line
			(start -0.15 -0.4)
			(end 0.15 -0.4)
			(stroke
				(width 0.15)
				(type solid)
			)
			(layer "F.SilkS")
		)
		(fp_line
			(start -0.15 0.4)
			(end 0.15 0.4)
			(stroke
				(width 0.15)
				(type solid)
			)
			(layer "F.SilkS")
		)
		(fp_rect
			(start -1.25 -0.65)
			(end 1.25 0.65)
			(stroke
				(width 0.05)
				(type solid)
			)
			(fill no)
			(layer "F.CrtYd")
		)
		(fp_line
			(start -0.803 0.406)
			(end -0.803 -0.408)
			(stroke
				(width 0.15)
				(type solid)
			)
			(layer "F.Fab")
		)
		(fp_line
			(start 0.8 -0.408)
			(end -0.803 -0.408)
			(stroke
				(width 0.15)
				(type solid)
			)
			(layer "F.Fab")
		)
		(fp_line
			(start 0.8 -0.408)
			(end 0.8 0.406)
			(stroke
				(width 0.15)
				(type solid)
			)
			(layer "F.Fab")
		)
		(fp_line
			(start 0.8 0.406)
			(end -0.803 0.406)
			(stroke
				(width 0.15)
				(type solid)
			)
			(layer "F.Fab")
		)
		(pad "1" smd roundrect
			(at -0.7 0)
			(size 0.8 1)
			(layers "F.Cu" "F.Mask" "F.Paste")
			(roundrect_rratio 0.2)
			(net 27 "/VBUS")
			(pintype "passive")
		)
		(pad "2" smd roundrect
			(at 0.7 0)
			(size 0.8 1)
			(layers "F.Cu" "F.Mask" "F.Paste")
			(roundrect_rratio 0.2)
			(net 26 "+5V")
			(pintype "passive")
		)
	)
	(footprint "antmicro-footprints:TP_SMD_1.5mm"
		(locked yes)
		(layer "F.Cu")
		(at 191 116)
		(property "Reference" "TP1"
			(at -1.588 -1.193 0)
			(layer "F.SilkS")
			(hide yes)
			(effects
				(font
					(size 0.7 0.7)
					(thickness 0.15)
				)
				(justify left bottom)
			)
		)
		(property "Value" "TP_1.5mm_SMD"
			(at 0 1.7 0)
			(layer "F.Fab")
			(effects
				(font
					(size 0.7 0.7)
					(thickness 0.15)
				)
				(justify left bottom)
			)
		)
		(property "Description" "test point, SMT"
			(at 0 0 0)
			(layer "F.Fab")
			(hide yes)
			(effects
				(font
					(size 1.27 1.27)
					(thickness 0.15)
				)
			)
		)
		(property "Author" "Antmicro"
			(at 0 0 0)
			(layer "F.Fab")
			(hide yes)
			(effects
				(font
					(size 1 1)
					(thickness 0.15)
				)
			)
		)
		(property "License" "Apache-2.0"
			(at 0 0 0)
			(layer "F.Fab")
			(hide yes)
			(effects
				(font
					(size 1 1)
					(thickness 0.15)
				)
			)
		)
		(property "MPN" ""
			(at 0 0 0)
			(layer "F.Fab")
			(hide yes)
			(effects
				(font
					(size 1 1)
					(thickness 0.15)
				)
			)
		)
		(property "Manufacturer" ""
			(at 0 0 0)
			(layer "F.Fab")
			(hide yes)
			(effects
				(font
					(size 1 1)
					(thickness 0.15)
				)
			)
		)
		(property "Public" "False"
			(at 0 0 0)
			(layer "F.Fab")
			(hide yes)
			(effects
				(font
					(size 1 1)
					(thickness 0.15)
				)
			)
		)
		(sheetfile "environment-sensor.kicad_sch")
		(attr exclude_from_pos_files)
		(pad "1" smd circle
			(at 0 0 270)
			(size 1.5 1.5)
			(layers "F.Cu" "F.Mask")
			(net 14 "NRST")
			(pinfunction "1")
			(pintype "passive")
		)
	)
	(footprint "antmicro-footprints:LQFP-48_7x7mm_P0.5mm"
		(layer "F.Cu")
		(at 191.6 131.95)
		(property "Reference" "U3"
			(at 3.6 -3.536 0)
			(layer "F.SilkS")
			(effects
				(font
					(size 0.7 0.7)
					(thickness 0.15)
				)
				(justify left bottom)
			)
		)
		(property "Value" "STM32G474CET6"
			(at 0 6 0)
			(layer "F.Fab")
			(effects
				(font
					(size 0.7 0.7)
					(thickness 0.15)
				)
				(justify left bottom)
			)
		)
		(property "Description" "ARM MCU, STM32 Family STM32G4 Series Microcontrollers, ARM Cortex-M4F, 32 bit, 170 MHz, 512 KB"
			(at 0 0 0)
			(layer "F.Fab")
			(hide yes)
			(effects
				(font
					(size 1.27 1.27)
					(thickness 0.15)
				)
			)
		)
		(property "Author" "Antmicro"
			(at 0 0 0)
			(layer "F.Fab")
			(hide yes)
			(effects
				(font
					(size 1 1)
					(thickness 0.15)
				)
			)
		)
		(property "License" "Apache-2.0"
			(at 0 0 0)
			(layer "F.Fab")
			(hide yes)
			(effects
				(font
					(size 1 1)
					(thickness 0.15)
				)
			)
		)
		(property "MPN" "STM32G474CET6"
			(at 0 0 0)
			(layer "F.Fab")
			(hide yes)
			(effects
				(font
					(size 1 1)
					(thickness 0.15)
				)
			)
		)
		(property "Manufacturer" "STMicroelectronics"
			(at 0 0 0)
			(layer "F.Fab")
			(hide yes)
			(effects
				(font
					(size 1 1)
					(thickness 0.15)
				)
			)
		)
		(sheetfile "environment-sensor.kicad_sch")
		(attr smd)
		(fp_line
			(start -3.6 3.164)
			(end -3.6 3.664)
			(stroke
				(width 0.15)
				(type solid)
			)
			(layer "F.SilkS")
		)
		(fp_line
			(start -3.6 3.664)
			(end -3.1 3.664)
			(stroke
				(width 0.15)
				(type solid)
			)
			(layer "F.SilkS")
		)
		(fp_line
			(start -3.1 -3.536)
			(end -3.6 -3.036)
			(stroke
				(width 0.15)
				(type solid)
			)
			(layer "F.SilkS")
		)
		(fp_line
			(start 3.1 -3.536)
			(end 3.6 -3.536)
			(stroke
				(width 0.15)
				(type solid)
			)
			(layer "F.SilkS")
		)
		(fp_line
			(start 3.6 -3.536)
			(end 3.6 -3.036)
			(stroke
				(width 0.15)
				(type solid)
			)
			(layer "F.SilkS")
		)
		(fp_line
			(start 3.6 3.164)
			(end 3.6 3.664)
			(stroke
				(width 0.15)
				(type solid)
			)
			(layer "F.SilkS")
		)
		(fp_line
			(start 3.6 3.664)
			(end 3.1 3.664)
			(stroke
				(width 0.15)
				(type solid)
			)
			(layer "F.SilkS")
		)
		(fp_circle
			(center -4.15 -3.035)
			(end -4.1 -3.035)
			(stroke
				(width 0.15)
				(type solid)
			)
			(fill yes)
			(layer "F.SilkS")
		)
		(fp_rect
			(start -4.85 -4.8)
			(end 4.85 4.9)
			(stroke
				(width 0.05)
				(type solid)
			)
			(fill no)
			(layer "F.CrtYd")
		)
		(fp_line
			(start -3.5 -2.936)
			(end -3.5 3.564)
			(stroke
				(width 0.15)
				(type solid)
			)
			(layer "F.Fab")
		)
		(fp_line
			(start -3.5 3.564)
			(end 3.5 3.564)
			(stroke
				(width 0.15)
				(type solid)
			)
			(layer "F.Fab")
		)
		(fp_line
			(start -3 -3.436)
			(end -3.5 -2.936)
			(stroke
				(width 0.15)
				(type solid)
			)
			(layer "F.Fab")
		)
		(fp_line
			(start -3 -3.436)
			(end 3.5 -3.436)
			(stroke
				(width 0.15)
				(type solid)
			)
			(layer "F.Fab")
		)
		(fp_line
			(start 3.5 -3.436)
			(end 3.5 3.564)
			(stroke
				(width 0.15)
				(type solid)
			)
			(layer "F.Fab")
		)
		(pad "1" smd rect
			(at -4.2 -2.685)
			(size 1.2 0.35)
			(layers "F.Cu" "F.Mask" "F.Paste")
			(net 28 "Net-(U3-VBAT)")
			(pinfunction "VBAT")
			(pintype "power_in")
		)
		(pad "2" smd rect
			(at -4.2 -2.185)
			(size 1.2 0.35)
			(layers "F.Cu" "F.Mask" "F.Paste")
			(net 21 "/FTDI_USER_PB")
			(pinfunction "PC13")
			(pintype "bidirectional")
		)
		(pad "3" smd rect
			(at -4.2 -1.685)
			(size 1.2 0.35)
			(layers "F.Cu" "F.Mask" "F.Paste")
			(net 86 "/OSC32_IN")
			(pinfunction "PC14-OSC32_IN")
			(pintype "bidirectional")
		)
		(pad "4" smd rect
			(at -4.2 -1.185)
			(size 1.2 0.35)
			(layers "F.Cu" "F.Mask" "F.Paste")
			(net 87 "/OSC32_OUT")
			(pinfunction "PC15-OSC32_OUT")
			(pintype "bidirectional")
		)
		(pad "5" smd rect
			(at -4.2 -0.685)
			(size 1.2 0.35)
			(layers "F.Cu" "F.Mask" "F.Paste")
			(net 33 "Net-(U3-PF0-OSC_IN)")
			(pinfunction "PF0-OSC_IN")
			(pintype "bidirectional")
		)
		(pad "6" smd rect
			(at -4.2 -0.185)
			(size 1.2 0.35)
			(layers "F.Cu" "F.Mask" "F.Paste")
			(net 31 "Net-(U3-PF1-OSC_OUT)")
			(pinfunction "PF1-OSC_OUT")
			(pintype "bidirectional")
		)
		(pad "7" smd rect
			(at -4.2 0.315)
			(size 1.2 0.35)
			(layers "F.Cu" "F.Mask" "F.Paste")
			(net 14 "NRST")
			(pinfunction "PG10-NRST")
			(pintype "bidirectional")
		)
		(pad "8" smd rect
			(at -4.2 0.815)
			(size 1.2 0.35)
			(layers "F.Cu" "F.Mask" "F.Paste")
			(net 84 "unconnected-(U3-PA0-Pad8)")
			(pinfunction "PA0")
			(pintype "bidirectional+no_connect")
		)
		(pad "9" smd rect
			(at -4.2 1.315)
			(size 1.2 0.35)
			(layers "F.Cu" "F.Mask" "F.Paste")
			(net 83 "unconnected-(U3-PA1-Pad9)")
			(pinfunction "PA1")
			(pintype "bidirectional+no_connect")
		)
		(pad "10" smd rect
			(at -4.2 1.815)
			(size 1.2 0.35)
			(layers "F.Cu" "F.Mask" "F.Paste")
			(net 17 "LPUART_1_STM_TX")
			(pinfunction "PA2")
			(pintype "bidirectional")
		)
		(pad "11" smd rect
			(at -4.2 2.315)
			(size 1.2 0.35)
			(layers "F.Cu" "F.Mask" "F.Paste")
			(net 16 "LPUART_1_STM_RX")
			(pinfunction "PA3")
			(pintype "bidirectional")
		)
		(pad "12" smd rect
			(at -4.2 2.815)
			(size 1.2 0.35)
			(layers "F.Cu" "F.Mask" "F.Paste")
			(net 82 "unconnected-(U3-PA4-Pad12)")
			(pinfunction "PA4")
			(pintype "bidirectional+no_connect")
		)
		(pad "13" smd rect
			(at -2.75 4.265)
			(size 0.35 1.2)
			(layers "F.Cu" "F.Mask" "F.Paste")
			(net 12 "/LD2")
			(pinfunction "PA5")
			(pintype "bidirectional")
		)
		(pad "14" smd rect
			(at -2.25 4.265)
			(size 0.35 1.2)
			(layers "F.Cu" "F.Mask" "F.Paste")
			(net 81 "unconnected-(U3-PA6-Pad14)")
			(pinfunction "PA6")
			(pintype "bidirectional+no_connect")
		)
		(pad "15" smd rect
			(at -1.75 4.265)
			(size 0.35 1.2)
			(layers "F.Cu" "F.Mask" "F.Paste")
			(net 80 "unconnected-(U3-PA7-Pad15)")
			(pinfunction "PA7")
			(pintype "bidirectional+no_connect")
		)
		(pad "16" smd rect
			(at -1.25 4.265)
			(size 0.35 1.2)
			(layers "F.Cu" "F.Mask" "F.Paste")
			(net 79 "unconnected-(U3-PB0-Pad16)")
			(pinfunction "PB0")
			(pintype "bidirectional+no_connect")
		)
		(pad "17" smd rect
			(at -0.75 4.265)
			(size 0.35 1.2)
			(layers "F.Cu" "F.Mask" "F.Paste")
			(net 78 "unconnected-(U3-PB1-Pad17)")
			(pinfunction "PB1")
			(pintype "bidirectional+no_connect")
		)
		(pad "18" smd rect
			(at -0.25 4.265)
			(size 0.35 1.2)
			(layers "F.Cu" "F.Mask" "F.Paste")
			(net 77 "unconnected-(U3-PB2-Pad18)")
			(pinfunction "PB2")
			(pintype "bidirectional+no_connect")
		)
		(pad "19" smd rect
			(at 0.25 4.265)
			(size 0.35 1.2)
			(layers "F.Cu" "F.Mask" "F.Paste")
			(net 1 "GND")
			(pinfunction "VSSA")
			(pintype "power_in")
		)
		(pad "20" smd rect
			(at 0.75 4.265)
			(size 0.35 1.2)
			(layers "F.Cu" "F.Mask" "F.Paste")
			(net 32 "Net-(U3-VREF+)")
			(pinfunction "VREF+")
			(pintype "passive")
		)
		(pad "21" smd rect
			(at 1.25 4.265)
			(size 0.35 1.2)
			(layers "F.Cu" "F.Mask" "F.Paste")
			(net 30 "Net-(U3-VDDA)")
			(pinfunction "VDDA")
			(pintype "power_in")
		)
		(pad "22" smd rect
			(at 1.75 4.265)
			(size 0.35 1.2)
			(layers "F.Cu" "F.Mask" "F.Paste")
			(net 76 "unconnected-(U3-PB10-Pad22)")
			(pinfunction "PB10")
			(pintype "bidirectional+no_connect")
		)
		(pad "23" smd rect
			(at 2.25 4.265)
			(size 0.35 1.2)
			(layers "F.Cu" "F.Mask" "F.Paste")
			(net 1 "GND")
			(pinfunction "VSS")
			(pintype "power_in")
		)
		(pad "24" smd rect
			(at 2.75 4.265)
			(size 0.35 1.2)
			(layers "F.Cu" "F.Mask" "F.Paste")
			(net 2 "+3V3")
			(pinfunction "VDD")
			(pintype "power_in")
		)
		(pad "25" smd rect
			(at 4.2 2.815)
			(size 1.2 0.35)
			(layers "F.Cu" "F.Mask" "F.Paste")
			(net 15 "/FRAM_WP")
			(pinfunction "PB11")
			(pintype "bidirectional")
		)
		(pad "26" smd rect
			(at 4.2 2.315)
			(size 1.2 0.35)
			(layers "F.Cu" "F.Mask" "F.Paste")
			(net 75 "unconnected-(U3-PB12-Pad26)")
			(pinfunction "PB12")
			(pintype "bidirectional+no_connect")
		)
		(pad "27" smd rect
			(at 4.2 1.815)
			(size 1.2 0.35)
			(layers "F.Cu" "F.Mask" "F.Paste")
			(net 74 "unconnected-(U3-PB13-Pad27)")
			(pinfunction "PB13")
			(pintype "bidirectional+no_connect")
		)
		(pad "28" smd rect
			(at 4.2 1.315)
			(size 1.2 0.35)
			(layers "F.Cu" "F.Mask" "F.Paste")
			(net 73 "unconnected-(U3-PB14-Pad28)")
			(pinfunction "PB14")
			(pintype "bidirectional+no_connect")
		)
		(pad "29" smd rect
			(at 4.2 0.815)
			(size 1.2 0.35)
			(layers "F.Cu" "F.Mask" "F.Paste")
			(net 72 "unconnected-(U3-PB15-Pad29)")
			(pinfunction "PB15")
			(pintype "bidirectional+no_connect")
		)
		(pad "30" smd rect
			(at 4.2 0.315)
			(size 1.2 0.35)
			(layers "F.Cu" "F.Mask" "F.Paste")
			(net 47 "Net-(U3-PA8)")
			(pinfunction "PA8")
			(pintype "bidirectional")
		)
		(pad "31" smd rect
			(at 4.2 -0.185)
			(size 1.2 0.35)
			(layers "F.Cu" "F.Mask" "F.Paste")
			(net 48 "Net-(U3-PA9)")
			(pinfunction "PA9")
			(pintype "bidirectional")
		)
		(pad "32" smd rect
			(at 4.2 -0.685)
			(size 1.2 0.35)
			(layers "F.Cu" "F.Mask" "F.Paste")
			(net 71 "unconnected-(U3-PA10-Pad32)")
			(pinfunction "PA10")
			(pintype "bidirectional+no_connect")
		)
		(pad "33" smd rect
			(at 4.2 -1.185)
			(size 1.2 0.35)
			(layers "F.Cu" "F.Mask" "F.Paste")
			(net 70 "unconnected-(U3-PA11-Pad33)")
			(pinfunction "PA11")
			(pintype "bidirectional+no_connect")
		)
		(pad "34" smd rect
			(at 4.2 -1.685)
			(size 1.2 0.35)
			(layers "F.Cu" "F.Mask" "F.Paste")
			(net 69 "unconnected-(U3-PA12-Pad34)")
			(pinfunction "PA12")
			(pintype "bidirectional+no_connect")
		)
		(pad "35" smd rect
			(at 4.2 -2.185)
			(size 1.2 0.35)
			(layers "F.Cu" "F.Mask" "F.Paste")
			(net 1 "GND")
			(pinfunction "VSS")
			(pintype "passive")
		)
		(pad "36" smd rect
			(at 4.2 -2.685)
			(size 1.2 0.35)
			(layers "F.Cu" "F.Mask" "F.Paste")
			(net 2 "+3V3")
			(pinfunction "VDD")
			(pintype "passive")
		)
		(pad "37" smd rect
			(at 2.75 -4.135)
			(size 0.35 1.2)
			(layers "F.Cu" "F.Mask" "F.Paste")
			(net 20 "SWDIO-JTMS")
			(pinfunction "PA13")
			(pintype "bidirectional")
		)
		(pad "38" smd rect
			(at 2.25 -4.135)
			(size 0.35 1.2)
			(layers "F.Cu" "F.Mask" "F.Paste")
			(net 18 "SWCLK-JTCK")
			(pinfunction "PA14")
			(pintype "bidirectional")
		)
		(pad "39" smd rect
			(at 1.75 -4.135)
			(size 0.35 1.2)
			(layers "F.Cu" "F.Mask" "F.Paste")
			(net 46 "Net-(U3-PA15)")
			(pinfunction "PA15")
			(pintype "bidirectional")
		)
		(pad "40" smd rect
			(at 1.25 -4.135)
			(size 0.35 1.2)
			(layers "F.Cu" "F.Mask" "F.Paste")
			(net 19 "JTDO")
			(pinfunction "PB3")
			(pintype "bidirectional")
		)
		(pad "41" smd rect
			(at 0.75 -4.135)
			(size 0.35 1.2)
			(layers "F.Cu" "F.Mask" "F.Paste")
			(net 13 "JTRST")
			(pinfunction "PB4")
			(pintype "bidirectional")
		)
		(pad "42" smd rect
			(at 0.25 -4.135)
			(size 0.35 1.2)
			(layers "F.Cu" "F.Mask" "F.Paste")
			(net 68 "unconnected-(U3-PB5-Pad42)")
			(pinfunction "PB5")
			(pintype "bidirectional+no_connect")
		)
		(pad "43" smd rect
			(at -0.25 -4.135)
			(size 0.35 1.2)
			(layers "F.Cu" "F.Mask" "F.Paste")
			(net 67 "unconnected-(U3-PB6-Pad43)")
			(pinfunction "PB6")
			(pintype "bidirectional+no_connect")
		)
		(pad "44" smd rect
			(at -0.75 -4.135)
			(size 0.35 1.2)
			(layers "F.Cu" "F.Mask" "F.Paste")
			(net 66 "unconnected-(U3-PB7-Pad44)")
			(pinfunction "PB7")
			(pintype "bidirectional+no_connect")
		)
		(pad "45" smd rect
			(at -1.25 -4.135)
			(size 0.35 1.2)
			(layers "F.Cu" "F.Mask" "F.Paste")
			(net 49 "Net-(U3-PB8-BOOT0)")
			(pinfunction "PB8-BOOT0")
			(pintype "bidirectional")
		)
		(pad "46" smd rect
			(at -1.75 -4.135)
			(size 0.35 1.2)
			(layers "F.Cu" "F.Mask" "F.Paste")
			(net 50 "Net-(U3-PB9)")
			(pinfunction "PB9")
			(pintype "bidirectional")
		)
		(pad "47" smd rect
			(at -2.25 -4.135)
			(size 0.35 1.2)
			(layers "F.Cu" "F.Mask" "F.Paste")
			(net 1 "GND")
			(pinfunction "VSS")
			(pintype "passive")
		)
		(pad "48" smd rect
			(at -2.75 -4.135)
			(size 0.35 1.2)
			(layers "F.Cu" "F.Mask" "F.Paste")
			(net 2 "+3V3")
			(pinfunction "VDD")
			(pintype "passive")
		)
	)
)
